# S9S_MB_2U (Grand Teton) — schematic netlist excerpt (pin names and nets, part order shuffled) for the footprints in the layout excerpt that follows; sources: Cadence DE-HDL packaged netlist, KiCad conversion of 03242023_DA0F0TMBIJ0_F0T_Motherboard_J_brd_V01_OCP.brd

C323  Q_CAP  47UF 4V 20% X6S  pkg C0805  page 78 : A = PVCCIN_CPU1 ; B = GND
R1306  Q_RES  33.2 1% CHIP  pkg 0402LF  page 205 : A = FM_PS_PWROK_DLY_R_SEL ; B = FM_PS_PWROK_DLY_SEL
C550  Q_CAP  1UF 25V 10% X6S  pkg C0402  page 131 : A = P1V8_PCH_AUX ; B = GND

(kicad_pcb
	(version 20260206)
	(generator "pcbnew")
	(generator_version "10.0")
	(general
		(thickness 1.6)
		(legacy_teardrops no)
	)
	(paper "A4")
	(title_block
		(title "03242023_DA0F0TMBIJ0_F0T_Motherboard_J_brd_V01_OCP.brd")
		(comment 1 "Grand Teton / footprints 5580-5582 of 6105")
	)
	(layers
		(0 "F.Cu" signal "TOP")
		(4 "In1.Cu" signal "GND")
		(6 "In2.Cu" signal "IN1")
		(8 "In3.Cu" signal "GND1")
		(10 "In4.Cu" signal "IN2")
		(12 "In5.Cu" signal "GND2")
		(14 "In6.Cu" signal "IN3")
		(16 "In7.Cu" signal "GND3")
		(18 "In8.Cu" signal "VCC")
		(20 "In9.Cu" signal "VCC1")
		(22 "In10.Cu" signal "GND4")
		(24 "In11.Cu" signal "IN4")
		(26 "In12.Cu" signal "GND5")
		(28 "In13.Cu" signal "IN5")
		(30 "In14.Cu" signal "GND6")
		(32 "In15.Cu" signal "IN6")
		(34 "In16.Cu" signal "GND7")
		(2 "B.Cu" signal "BOTTOM")
		(9 "F.Adhes" user "F.Adhesive")
		(11 "B.Adhes" user "B.Adhesive")
		(13 "F.Paste" user "Package Geometry/Pastemask Top")
		(15 "B.Paste" user "Package Geometry/Pastemask Bottom")
		(5 "F.SilkS" user "Ref Des/Silkscreen Top")
		(7 "B.SilkS" user "Ref Des/Silkscreen Bottom")
		(1 "F.Mask" user "Board Geometry/Soldermask Top")
		(3 "B.Mask" user "Board Geometry/Soldermask Bottom")
		(17 "Dwgs.User" user "User.Drawings")
		(19 "Cmts.User" user "User.Comments")
		(21 "Eco1.User" user "User.Eco1")
		(23 "Eco2.User" user "User.Eco2")
		(25 "Edge.Cuts" user "Board Geometry/Outline")
		(27 "Margin" user)
		(31 "F.CrtYd" user "Package Geometry/Place Bound Top")
		(29 "B.CrtYd" user "Package Geometry/Place Bound Bottom")
		(35 "F.Fab" user "Ref Des/Assembly Top")
		(33 "B.Fab" user "Ref Des/Assembly Bottom")
	)
	(footprint ""
		(layer "B.Cu")
		(at 118.18112 -248.49836 -90)
		(property "Reference" "C323"
			(at 0 0 90)
			(layer "B.SilkS")
			(hide yes)
			(effects
				(font
					(size 1.27 1.27)
				)
				(justify mirror)
			)
		)
		(property "Value" ""
			(at 0 0 90)
			(layer "B.Fab")
			(effects
				(font
					(size 1.27 1.27)
				)
				(justify mirror)
			)
		)
		(duplicate_pad_numbers_are_jumpers no)
		(fp_line
			(start -1.524 0.762)
			(end 1.524 0.762)
			(stroke
				(width 0.1524)
				(type default)
			)
			(layer "B.SilkS")
		)
		(fp_line
			(start 1.524 0.762)
			(end 1.524 -0.762)
			(stroke
				(width 0.1524)
				(type default)
			)
			(layer "B.SilkS")
		)
		(fp_line
			(start -1.524 -0.762)
			(end -1.524 0.762)
			(stroke
				(width 0.1524)
				(type default)
			)
			(layer "B.SilkS")
		)
		(fp_line
			(start 1.524 -0.762)
			(end -1.524 -0.762)
			(stroke
				(width 0.1524)
				(type default)
			)
			(layer "B.SilkS")
		)
		(fp_line
			(start -1.1049 0.724916)
			(end -1.1049 -0.724916)
			(stroke
				(width 0.1)
				(type default)
			)
			(layer "B.Fab")
		)
		(fp_line
			(start 1.1049 0.724916)
			(end -1.1049 0.724916)
			(stroke
				(width 0.1)
				(type default)
			)
			(layer "B.Fab")
		)
		(fp_line
			(start -1.1049 -0.724916)
			(end 1.1049 -0.724916)
			(stroke
				(width 0.1)
				(type default)
			)
			(layer "B.Fab")
		)
		(fp_line
			(start 1.1049 -0.724916)
			(end 1.1049 0.724916)
			(stroke
				(width 0.1)
				(type default)
			)
			(layer "B.Fab")
		)
		(pad "1" smd rect
			(at 0.889 0 270)
			(size 1.016 1.27)
			(layers "B.Cu" "B.Mask" "B.Paste")
			(net "PVCCIN_CPU1")
		)
		(pad "2" smd rect
			(at -0.889 0 270)
			(size 1.016 1.27)
			(layers "B.Cu" "B.Mask" "B.Paste")
			(net "GND")
		)
	)
	(footprint ""
		(layer "B.Cu")
		(at 341.272114 -30.636972 180)
		(property "Reference" "R1306"
			(at 0 0 0)
			(layer "B.SilkS")
			(hide yes)
			(effects
				(font
					(size 1.27 1.27)
				)
				(justify mirror)
			)
		)
		(property "Value" ""
			(at 0 0 0)
			(layer "B.Fab")
			(effects
				(font
					(size 1.27 1.27)
				)
				(justify mirror)
			)
		)
		(duplicate_pad_numbers_are_jumpers no)
		(fp_line
			(start 0.7874 0.4064)
			(end 0.7874 -0.4064)
			(stroke
				(width 0.1524)
				(type default)
			)
			(layer "B.SilkS")
		)
		(fp_line
			(start 0.7874 -0.4064)
			(end -0.7874 -0.4064)
			(stroke
				(width 0.1524)
				(type default)
			)
			(layer "B.SilkS")
		)
		(fp_line
			(start -0.7874 0.4064)
			(end 0.7874 0.4064)
			(stroke
				(width 0.1524)
				(type default)
			)
			(layer "B.SilkS")
		)
		(fp_line
			(start -0.7874 -0.4064)
			(end -0.7874 0.4064)
			(stroke
				(width 0.1524)
				(type default)
			)
			(layer "B.SilkS")
		)
		(fp_line
			(start 0.67945 0.3048)
			(end 0.67945 -0.305054)
			(stroke
				(width 0.1)
				(type default)
			)
			(layer "B.Fab")
		)
		(fp_line
			(start 0.67945 -0.305054)
			(end 0.12065 -0.305054)
			(stroke
				(width 0.1)
				(type default)
			)
			(layer "B.Fab")
		)
		(fp_line
			(start 0.12065 0.3048)
			(end 0.67945 0.3048)
			(stroke
				(width 0.1)
				(type default)
			)
			(layer "B.Fab")
		)
		(fp_line
			(start 0.12065 0.2794)
			(end 0.12065 0.3048)
			(stroke
				(width 0.1)
				(type default)
			)
			(layer "B.Fab")
		)
		(fp_line
			(start 0.12065 -0.2794)
			(end -0.12065 -0.2794)
			(stroke
				(width 0.1)
				(type default)
			)
			(layer "B.Fab")
		)
		(fp_line
			(start 0.12065 -0.305054)
			(end 0.12065 -0.2794)
			(stroke
				(width 0.1)
				(type default)
			)
			(layer "B.Fab")
		)
		(fp_line
			(start -0.120396 0.3048)
			(end -0.120396 0.2794)
			(stroke
				(width 0.1)
				(type default)
			)
			(layer "B.Fab")
		)
		(fp_line
			(start -0.120396 0.2794)
			(end 0.12065 0.2794)
			(stroke
				(width 0.1)
				(type default)
			)
			(layer "B.Fab")
		)
		(fp_line
			(start -0.12065 -0.2794)
			(end -0.12065 -0.3048)
			(stroke
				(width 0.1)
				(type default)
			)
			(layer "B.Fab")
		)
		(fp_line
			(start -0.12065 -0.3048)
			(end -0.67945 -0.3048)
			(stroke
				(width 0.1)
				(type default)
			)
			(layer "B.Fab")
		)
		(fp_line
			(start -0.67945 0.3048)
			(end -0.120396 0.3048)
			(stroke
				(width 0.1)
				(type default)
			)
			(layer "B.Fab")
		)
		(fp_line
			(start -0.67945 -0.3048)
			(end -0.67945 0.3048)
			(stroke
				(width 0.1)
				(type default)
			)
			(layer "B.Fab")
		)
		(pad "1" smd circle
			(at 0.40005 0)
			(size 0 0)
			(layers "B.Cu" "B.Mask" "B.Paste")
			(net "FM_PS_PWROK_DLY_R_SEL")
		)
		(pad "2" smd circle
			(at -0.40005 0)
			(size 0 0)
			(layers "B.Cu" "B.Mask" "B.Paste")
			(net "FM_PS_PWROK_DLY_SEL")
		)
	)
	(footprint ""
		(layer "B.Cu")
		(at 396.97406 -61.448188 90)
		(property "Reference" "C550"
			(at 0 0 90)
			(layer "B.SilkS")
			(hide yes)
			(effects
				(font
					(size 1.27 1.27)
				)
				(justify mirror)
			)
		)
		(property "Value" ""
			(at 0 0 90)
			(layer "B.Fab")
			(effects
				(font
					(size 1.27 1.27)
				)
				(justify mirror)
			)
		)
		(duplicate_pad_numbers_are_jumpers no)
		(fp_line
			(start 0.7874 -0.4064)
			(end -0.7874 -0.4064)
			(stroke
				(width 0.1524)
				(type default)
			)
			(layer "B.SilkS")
		)
		(fp_line
			(start -0.7874 -0.4064)
			(end -0.7874 0.4064)
			(stroke
				(width 0.1524)
				(type default)
			)
			(layer "B.SilkS")
		)
		(fp_line
			(start 0.7874 0.4064)
			(end 0.7874 -0.4064)
			(stroke
				(width 0.1524)
				(type default)
			)
			(layer "B.SilkS")
		)
		(fp_line
			(start -0.7874 0.4064)
			(end 0.7874 0.4064)
			(stroke
				(width 0.1524)
				(type default)
			)
			(layer "B.SilkS")
		)
		(fp_line
			(start 0.67945 -0.305054)
			(end 0.12065 -0.305054)
			(stroke
				(width 0.1)
				(type default)
			)
			(layer "B.Fab")
		)
		(fp_line
			(start 0.12065 -0.305054)
			(end 0.12065 -0.2794)
			(stroke
				(width 0.1)
				(type default)
			)
			(layer "B.Fab")
		)
		(fp_line
			(start -0.12065 -0.3048)
			(end -0.67945 -0.3048)
			(stroke
				(width 0.1)
				(type default)
			)
			(layer "B.Fab")
		)
		(fp_line
			(start -0.67945 -0.3048)
			(end -0.67945 0.3048)
			(stroke
				(width 0.1)
				(type default)
			)
			(layer "B.Fab")
		)
		(fp_line
			(start 0.12065 -0.2794)
			(end -0.12065 -0.2794)
			(stroke
				(width 0.1)
				(type default)
			)
			(layer "B.Fab")
		)
		(fp_line
			(start -0.12065 -0.2794)
			(end -0.12065 -0.3048)
			(stroke
				(width 0.1)
				(type default)
			)
			(layer "B.Fab")
		)
		(fp_line
			(start 0.12065 0.2794)
			(end 0.12065 0.3048)
			(stroke
				(width 0.1)
				(type default)
			)
			(layer "B.Fab")
		)
		(fp_line
			(start -0.120396 0.2794)
			(end 0.12065 0.2794)
			(stroke
				(width 0.1)
				(type default)
			)
			(layer "B.Fab")
		)
		(fp_line
			(start 0.67945 0.3048)
			(end 0.67945 -0.305054)
			(stroke
				(width 0.1)
				(type default)
			)
			(layer "B.Fab")
		)
		(fp_line
			(start 0.12065 0.3048)
			(end 0.67945 0.3048)
			(stroke
				(width 0.1)
				(type default)
			)
			(layer "B.Fab")
		)
		(fp_line
			(start -0.120396 0.3048)
			(end -0.120396 0.2794)
			(stroke
				(width 0.1)
				(type default)
			)
			(layer "B.Fab")
		)
		(fp_line
			(start -0.67945 0.3048)
			(end -0.120396 0.3048)
			(stroke
				(width 0.1)
				(type default)
			)
			(layer "B.Fab")
		)
		(pad "1" smd circle
			(at 0.40005 0 270)
			(size 0 0)
			(layers "B.Cu" "B.Mask" "B.Paste")
			(net "P1V8_PCH_AUX")
		)
		(pad "2" smd circle
			(at -0.40005 0 270)
			(size 0 0)
			(layers "B.Cu" "B.Mask" "B.Paste")
			(net "GND")
		)
	)
)
